(kicad_pcb
	(version 20211014)
	(generator pcbnew)
	(general
    (thickness 1.6)
  )
	(paper "A4")
	(title_block
    (title "SA800U (Snapdragon 845) Baseboard")
    (date "2023-10-19")
    (rev "1.0.3")
    (company "Antmicro Ltd.")
    (comment 1 "www.antmicro.com")
		(comment 9 "footprints 24-32 of 589")
	)
	(layers
    (0 "F.Cu" signal)
    (1 "In1.Cu" power)
    (2 "In2.Cu" signal)
    (3 "In3.Cu" signal)
    (4 "In4.Cu" power)
    (31 "B.Cu" signal)
    (32 "B.Adhes" user "B.Adhesive")
    (33 "F.Adhes" user "F.Adhesive")
    (34 "B.Paste" user)
    (35 "F.Paste" user)
    (36 "B.SilkS" user "B.Silkscreen")
    (37 "F.SilkS" user "F.Silkscreen")
    (38 "B.Mask" user)
    (39 "F.Mask" user)
    (40 "Dwgs.User" user "User.Drawings")
    (41 "Cmts.User" user "User.Comments")
    (42 "Eco1.User" user "User.Eco1")
    (43 "Eco2.User" user "User.Eco2")
    (44 "Edge.Cuts" user)
    (45 "Margin" user)
    (46 "B.CrtYd" user "B.Courtyard")
    (47 "F.CrtYd" user "F.Courtyard")
    (48 "B.Fab" user)
    (49 "F.Fab" user)
  )
	(footprint "sa800u-baseboard-hw-footprints:R_0402_1005Metric" (layer "F.Cu")
    (tedit 5FD9C158)
    (at 149.9 101.9 180)
    (descr "Resistor SMD 0402")
    (tags "resistor SMD 0402")
    (property "Author" "Antmicro")
    (property "License" "Apache-2.0")
    (property "MPN" "CR0402-FX-1001GLF")
    (property "Manufacturer" "Bourns")
    (property "Sheetfile" "som.kicad_sch")
    (property "Sheetname" "SoM")
    (property "Tolerance" "1%")
    (property "Val" "1k")
    (attr smd)
    (fp_text reference "R74" (at 3.06 -0.35 180) (layer "F.SilkS")
      (effects (font (size 0.7 0.7) (thickness 0.15)) (justify left bottom))
    )
    (fp_text value "R_1k_0402" (at 0 1.4 180) (layer "F.Fab")
      (effects (font (size 0.7 0.7) (thickness 0.15)) (justify left bottom))
    )
    (fp_text user "Author: Antmicro" (at -0.95 4.169 180) (layer "F.Fab") hide
      (effects (font (size 0.7 0.7) (thickness 0.15)) (justify left bottom))
    )
    (fp_text user "License: Apache-2.0" (at -0.95 5.169 180) (layer "F.Fab") hide
      (effects (font (size 0.7 0.7) (thickness 0.15)) (justify left bottom))
    )
    (fp_text user "${REFERENCE}" (at -0.95 3.168 180) (layer "F.Fab") hide
      (effects (font (size 0.7 0.7) (thickness 0.15)) (justify left bottom))
    )
    (fp_rect (start -0.93 -0.47) (end 0.93 0.47) (layer "F.CrtYd") (width 0.05) (fill none))
    (fp_rect (start -0.5 -0.25) (end 0.5 0.25) (layer "F.Fab") (width 0.15) (fill none))
    (pad "1" smd roundrect (at -0.485 0 180) (size 0.59 0.64) (layers "F.Cu" "F.Paste" "F.Mask") (roundrect_rratio 0.25)
      (net 345 "/SoM/VOL_UP_R") (pintype "passive"))
    (pad "2" smd roundrect (at 0.485 0 180) (size 0.59 0.64) (layers "F.Cu" "F.Paste" "F.Mask") (roundrect_rratio 0.25)
      (net 96 "VOL_UP") (pintype "passive"))
  )
	(footprint "sa800u-baseboard-hw-footprints:R_0402_1005Metric" (layer "F.Cu")
    (tedit 5FD9C158)
    (at 149.9 113.9 180)
    (descr "Resistor SMD 0402")
    (tags "resistor SMD 0402")
    (property "Author" "Antmicro")
    (property "License" "Apache-2.0")
    (property "MPN" "CR0402-FX-1001GLF")
    (property "Manufacturer" "Bourns")
    (property "Sheetfile" "som.kicad_sch")
    (property "Sheetname" "SoM")
    (property "Tolerance" "1%")
    (property "Val" "1k")
    (attr smd)
    (fp_text reference "R75" (at 1.15 -1.33 180) (layer "F.SilkS")
      (effects (font (size 0.7 0.7) (thickness 0.15)) (justify left bottom))
    )
    (fp_text value "R_1k_0402" (at 0 1.4 180) (layer "F.Fab")
      (effects (font (size 0.7 0.7) (thickness 0.15)) (justify left bottom))
    )
    (fp_text user "Author: Antmicro" (at -0.95 4.169 180) (layer "F.Fab") hide
      (effects (font (size 0.7 0.7) (thickness 0.15)) (justify left bottom))
    )
    (fp_text user "${REFERENCE}" (at -0.95 3.168 180) (layer "F.Fab") hide
      (effects (font (size 0.7 0.7) (thickness 0.15)) (justify left bottom))
    )
    (fp_text user "License: Apache-2.0" (at -0.95 5.169 180) (layer "F.Fab") hide
      (effects (font (size 0.7 0.7) (thickness 0.15)) (justify left bottom))
    )
    (fp_rect (start -0.93 -0.47) (end 0.93 0.47) (layer "F.CrtYd") (width 0.05) (fill none))
    (fp_rect (start -0.5 -0.25) (end 0.5 0.25) (layer "F.Fab") (width 0.15) (fill none))
    (pad "1" smd roundrect (at -0.485 0 180) (size 0.59 0.64) (layers "F.Cu" "F.Paste" "F.Mask") (roundrect_rratio 0.25)
      (net 346 "/SoM/PWR_R") (pintype "passive"))
    (pad "2" smd roundrect (at 0.485 0 180) (size 0.59 0.64) (layers "F.Cu" "F.Paste" "F.Mask") (roundrect_rratio 0.25)
      (net 95 "PWRKEY") (pintype "passive"))
  )
	(footprint "sa800u-baseboard-hw-footprints:R_0402_1005Metric" (layer "F.Cu")
    (tedit 5FD9C158)
    (at 71 119.6 90)
    (descr "Resistor SMD 0402")
    (tags "resistor SMD 0402")
    (property "Author" "Antmicro")
    (property "License" "Apache-2.0")
    (property "MPN" "CR0402-FX-2552GLF")
    (property "Manufacturer" "Bourns")
    (property "Sheetfile" "psu.kicad_sch")
    (property "Sheetname" "PSU")
    (property "Tolerance" "1%")
    (property "Val" "25k5")
    (attr smd)
    (fp_text reference "R129" (at -3.74 0.37 90) (layer "F.SilkS")
      (effects (font (size 0.7 0.7) (thickness 0.15)) (justify left bottom))
    )
    (fp_text value "R_25k5_0402" (at 0 1.4 90) (layer "F.Fab")
      (effects (font (size 0.7 0.7) (thickness 0.15)) (justify left bottom))
    )
    (fp_text user "Author: Antmicro" (at -0.95 4.169 90) (layer "F.Fab") hide
      (effects (font (size 0.7 0.7) (thickness 0.15)) (justify left bottom))
    )
    (fp_text user "${REFERENCE}" (at -0.95 3.168 90) (layer "F.Fab") hide
      (effects (font (size 0.7 0.7) (thickness 0.15)) (justify left bottom))
    )
    (fp_text user "License: Apache-2.0" (at -0.95 5.169 90) (layer "F.Fab") hide
      (effects (font (size 0.7 0.7) (thickness 0.15)) (justify left bottom))
    )
    (fp_rect (start -0.93 -0.47) (end 0.93 0.47) (layer "F.CrtYd") (width 0.05) (fill none))
    (fp_rect (start -0.5 -0.25) (end 0.5 0.25) (layer "F.Fab") (width 0.15) (fill none))
    (pad "1" smd roundrect (at -0.485 0 90) (size 0.59 0.64) (layers "F.Cu" "F.Paste" "F.Mask") (roundrect_rratio 0.25)
      (net 156 "/PSU/BYPASS_EN") (pintype "passive"))
    (pad "2" smd roundrect (at 0.485 0 90) (size 0.59 0.64) (layers "F.Cu" "F.Paste" "F.Mask") (roundrect_rratio 0.25)
      (net 164 "/PSU/5V_DC_DC_ENABLE") (pintype "passive"))
  )
	(footprint "sa800u-baseboard-hw-footprints:R_0402_1005Metric" (layer "F.Cu")
    (tedit 5FD9C158)
    (at 71.6 115.3 180)
    (descr "Resistor SMD 0402")
    (tags "resistor SMD 0402")
    (property "Author" "Antmicro")
    (property "License" "Apache-2.0")
    (property "MPN" "CR0402-FX-1002GLF")
    (property "Manufacturer" "Bourns")
    (property "Sheetfile" "psu.kicad_sch")
    (property "Sheetname" "PSU")
    (property "Tolerance" "1%")
    (property "Val" "10k")
    (attr smd)
    (fp_text reference "R130" (at -0.94 -4.74 180) (layer "F.SilkS")
      (effects (font (size 0.7 0.7) (thickness 0.15)) (justify left bottom))
    )
    (fp_text value "R_10k_0402" (at 0 1.4 180) (layer "F.Fab")
      (effects (font (size 0.7 0.7) (thickness 0.15)) (justify left bottom))
    )
    (fp_text user "License: Apache-2.0" (at -0.95 5.169 180) (layer "F.Fab") hide
      (effects (font (size 0.7 0.7) (thickness 0.15)) (justify left bottom))
    )
    (fp_text user "Author: Antmicro" (at -0.95 4.169 180) (layer "F.Fab") hide
      (effects (font (size 0.7 0.7) (thickness 0.15)) (justify left bottom))
    )
    (fp_text user "${REFERENCE}" (at -0.95 3.168 180) (layer "F.Fab") hide
      (effects (font (size 0.7 0.7) (thickness 0.15)) (justify left bottom))
    )
    (fp_rect (start -0.93 -0.47) (end 0.93 0.47) (layer "F.CrtYd") (width 0.05) (fill none))
    (fp_rect (start -0.5 -0.25) (end 0.5 0.25) (layer "F.Fab") (width 0.15) (fill none))
    (pad "1" smd roundrect (at -0.485 0 180) (size 0.59 0.64) (layers "F.Cu" "F.Paste" "F.Mask") (roundrect_rratio 0.25)
      (net 164 "/PSU/5V_DC_DC_ENABLE") (pintype "passive"))
    (pad "2" smd roundrect (at 0.485 0 180) (size 0.59 0.64) (layers "F.Cu" "F.Paste" "F.Mask") (roundrect_rratio 0.25)
      (net 1 "GND") (pintype "passive"))
  )
	(footprint "sa800u-baseboard-hw-footprints:R_0402_1005Metric" (layer "F.Cu")
    (tedit 5FD9C158)
    (at 71.6 116.3 180)
    (descr "Resistor SMD 0402")
    (tags "resistor SMD 0402")
    (property "Author" "Antmicro")
    (property "License" "Apache-2.0")
    (property "MPN" "CR0402-FX-1002GLF")
    (property "Manufacturer" "Bourns")
    (property "Sheetfile" "psu.kicad_sch")
    (property "Sheetname" "PSU")
    (property "Tolerance" "1%")
    (property "Val" "10k")
    (attr smd)
    (fp_text reference "R142" (at -0.94 -4.64 180) (layer "F.SilkS")
      (effects (font (size 0.7 0.7) (thickness 0.15)) (justify left bottom))
    )
    (fp_text value "R_10k_0402" (at 0 1.4 180) (layer "F.Fab")
      (effects (font (size 0.7 0.7) (thickness 0.15)) (justify left bottom))
    )
    (fp_text user "${REFERENCE}" (at -0.95 3.168 180) (layer "F.Fab") hide
      (effects (font (size 0.7 0.7) (thickness 0.15)) (justify left bottom))
    )
    (fp_text user "License: Apache-2.0" (at -0.95 5.169 180) (layer "F.Fab") hide
      (effects (font (size 0.7 0.7) (thickness 0.15)) (justify left bottom))
    )
    (fp_text user "Author: Antmicro" (at -0.95 4.169 180) (layer "F.Fab") hide
      (effects (font (size 0.7 0.7) (thickness 0.15)) (justify left bottom))
    )
    (fp_rect (start -0.93 -0.47) (end 0.93 0.47) (layer "F.CrtYd") (width 0.05) (fill none))
    (fp_rect (start -0.5 -0.25) (end 0.5 0.25) (layer "F.Fab") (width 0.15) (fill none))
    (pad "1" smd roundrect (at -0.485 0 180) (size 0.59 0.64) (layers "F.Cu" "F.Paste" "F.Mask") (roundrect_rratio 0.25)
      (net 173 "Net-(R141-Pad2)") (pintype "passive"))
    (pad "2" smd roundrect (at 0.485 0 180) (size 0.59 0.64) (layers "F.Cu" "F.Paste" "F.Mask") (roundrect_rratio 0.25)
      (net 1 "GND") (pintype "passive"))
  )
	(footprint "sa800u-baseboard-hw-footprints:AP62301WU-7-TSOT23-6" (layer "F.Cu")
    (tedit 6215EA50)
    (at 74.65 111.8 90)
    (property "Author" "Antmicro")
    (property "License" "Apache-2.0")
    (property "MPN" "AP62301WU-7")
    (property "Manufacturer" "Diodes Incorporated")
    (property "Sheetfile" "psu.kicad_sch")
    (property "Sheetname" "PSU")
    (attr smd)
    (fp_text reference "U20" (at -2.43 -0.33 180) (layer "F.SilkS")
      (effects (font (size 0.7 0.7) (thickness 0.15)) (justify left bottom))
    )
    (fp_text value "AP62301WU-7" (at -0.005 2.6 90) (layer "F.Fab")
      (effects (font (size 0.7 0.7) (thickness 0.15)) (justify left bottom))
    )
    (fp_text user "${REFERENCE}" (at -1.893 6.168 90) (layer "F.Fab") hide
      (effects (font (size 0.7 0.7) (thickness 0.15)) (justify left bottom))
    )
    (fp_text user "Author: Antmicro" (at -1.893 7.368 90) (layer "F.Fab") hide
      (effects (font (size 0.7 0.7) (thickness 0.15)) (justify left bottom))
    )
    (fp_text user "License: Apache-2.0" (at -1.893 4.967 90) (layer "F.Fab") hide
      (effects (font (size 0.7 0.7) (thickness 0.15)) (justify left bottom))
    )
    (fp_line (start 1.48 -0.72) (end 1.38 -0.72) (layer "F.SilkS") (width 0.15))
    (fp_line (start 1.479 0.73) (end 1.38 0.73) (layer "F.SilkS") (width 0.15))
    (fp_line (start 1.48 -0.72) (end 1.479 0.73) (layer "F.SilkS") (width 0.15))
    (fp_line (start -1.4805 0.725) (end -1.3905 0.725) (layer "F.SilkS") (width 0.15))
    (fp_line (start -1.4805 0.725) (end -1.4795 -0.725) (layer "F.SilkS") (width 0.15))
    (fp_line (start -1.4795 -0.725) (end -1.3905 -0.725) (layer "F.SilkS") (width 0.15))
    (fp_circle (center -1.499 1.236) (end -1.45 1.236) (layer "F.SilkS") (width 0.15) (fill solid))
    (fp_rect (start -1.65 -1.61) (end 1.65 1.61) (layer "F.CrtYd") (width 0.05) (fill none))
    (fp_line (start -1.102 0.916) (end 1.523 0.916) (layer "F.Fab") (width 0.15))
    (fp_line (start -1.527 0.491) (end -1.527 -0.833) (layer "F.Fab") (width 0.15))
    (fp_line (start 1.523 -0.833) (end 1.523 0.916) (layer "F.Fab") (width 0.15))
    (fp_line (start -1.527 0.491) (end -1.102 0.916) (layer "F.Fab") (width 0.15))
    (fp_line (start -1.527 -0.833) (end 1.523 -0.833) (layer "F.Fab") (width 0.15))
    (pad "1" smd rect (at -0.952 1.18 90) (size 0.7 0.8) (layers "F.Cu" "F.Paste" "F.Mask")
      (net 1 "GND") (pinfunction "GND") (pintype "power_in"))
    (pad "2" smd rect (at -0.001 1.18 90) (size 0.7 0.8) (layers "F.Cu" "F.Paste" "F.Mask")
      (net 359 "Net-(C133-Pad2)") (pinfunction "SW") (pintype "power_out"))
    (pad "3" smd rect (at 0.947 1.18 90) (size 0.7 0.8) (layers "F.Cu" "F.Paste" "F.Mask")
      (net 74 "VDD") (pinfunction "VIN") (pintype "power_in"))
    (pad "4" smd rect (at 0.947 -1.18 90) (size 0.7 0.8) (layers "F.Cu" "F.Paste" "F.Mask")
      (net 410 "Net-(R137-Pad2)") (pinfunction "FB") (pintype "input"))
    (pad "5" smd rect (at -0.001 -1.18 90) (size 0.7 0.8) (layers "F.Cu" "F.Paste" "F.Mask")
      (net 407 "Net-(R127-Pad2)") (pinfunction "EN") (pintype "input"))
    (pad "6" smd rect (at -0.952 -1.18 90) (size 0.7 0.8) (layers "F.Cu" "F.Paste" "F.Mask")
      (net 358 "Net-(C133-Pad1)") (pinfunction "BST") (pintype "output"))
  )
	(footprint "sa800u-baseboard-hw-footprints:C_0402_1005Metric" (layer "F.Cu")
    (tedit 616D63CF)
    (at 86.8 139.875 -90)
    (descr "Capacitor SMD 0402")
    (tags "capacitor SMD 0402")
    (property "Author" "Antmicro")
    (property "Dielectric" "")
    (property "License" "Apache-2.0")
    (property "MPN" "C1005X6S1A105K050BC")
    (property "Manufacturer" "TDK")
    (property "Sheetfile" "usb-pd.kicad_sch")
    (property "Sheetname" "USB-PD")
    (property "Val" "1u")
    (property "Voltage" "")
    (attr smd)
    (fp_text reference "C156" (at 2.595 -3.37 -90) (layer "F.SilkS")
      (effects (font (size 0.7 0.7) (thickness 0.15)) (justify left bottom))
    )
    (fp_text value "C_1u_0402" (at 0 1.4 -90) (layer "F.Fab")
      (effects (font (size 0.7 0.7) (thickness 0.15)) (justify left bottom))
    )
    (fp_text user "License: Apache-2.0" (at -0.932 5.17 -90) (layer "F.Fab") hide
      (effects (font (size 0.7 0.7) (thickness 0.15)) (justify left bottom))
    )
    (fp_text user "Author: Antmicro" (at -0.932 4.17 -90) (layer "F.Fab") hide
      (effects (font (size 0.7 0.7) (thickness 0.15)) (justify left bottom))
    )
    (fp_text user "${REFERENCE}" (at -0.932 3.168 -90) (layer "F.Fab") hide
      (effects (font (size 0.7 0.7) (thickness 0.15)) (justify left bottom))
    )
    (fp_rect (start -0.94 -0.47) (end 0.94 0.47) (layer "F.CrtYd") (width 0.05) (fill none))
    (fp_rect (start -0.499 -0.249) (end 0.499 0.249) (layer "F.Fab") (width 0.15) (fill none))
    (pad "1" smd roundrect (at -0.484 0 270) (size 0.59 0.64) (layers "F.Cu" "F.Paste" "F.Mask") (roundrect_rratio 0.25)
      (net 140 "/USB-PD/VREG_1V2") (pintype "passive"))
    (pad "2" smd roundrect (at 0.484 0 270) (size 0.59 0.64) (layers "F.Cu" "F.Paste" "F.Mask") (roundrect_rratio 0.25)
      (net 1 "GND") (pintype "passive"))
  )
	(footprint "sa800u-baseboard-hw-footprints:C_0402_1005Metric" (layer "F.Cu")
    (tedit 616D63CF)
    (at 88.8 139.875 -90)
    (descr "Capacitor SMD 0402")
    (tags "capacitor SMD 0402")
    (property "Author" "Antmicro")
    (property "Dielectric" "")
    (property "License" "Apache-2.0")
    (property "MPN" "C1005X6S1A105K050BC")
    (property "Manufacturer" "TDK")
    (property "Sheetfile" "usb-pd.kicad_sch")
    (property "Sheetname" "USB-PD")
    (property "Val" "1u")
    (property "Voltage" "")
    (attr smd)
    (fp_text reference "C157" (at 2.595 -3.37 -90) (layer "F.SilkS")
      (effects (font (size 0.7 0.7) (thickness 0.15)) (justify left bottom))
    )
    (fp_text value "C_1u_0402" (at 0 1.4 -90) (layer "F.Fab")
      (effects (font (size 0.7 0.7) (thickness 0.15)) (justify left bottom))
    )
    (fp_text user "Author: Antmicro" (at -0.932 4.17 -90) (layer "F.Fab") hide
      (effects (font (size 0.7 0.7) (thickness 0.15)) (justify left bottom))
    )
    (fp_text user "${REFERENCE}" (at -0.932 3.168 -90) (layer "F.Fab") hide
      (effects (font (size 0.7 0.7) (thickness 0.15)) (justify left bottom))
    )
    (fp_text user "License: Apache-2.0" (at -0.932 5.17 -90) (layer "F.Fab") hide
      (effects (font (size 0.7 0.7) (thickness 0.15)) (justify left bottom))
    )
    (fp_rect (start -0.94 -0.47) (end 0.94 0.47) (layer "F.CrtYd") (width 0.05) (fill none))
    (fp_rect (start -0.499 -0.249) (end 0.499 0.249) (layer "F.Fab") (width 0.15) (fill none))
    (pad "1" smd roundrect (at -0.484 0 270) (size 0.59 0.64) (layers "F.Cu" "F.Paste" "F.Mask") (roundrect_rratio 0.25)
      (net 107 "/USB-PD/PD_VBUS") (pintype "passive"))
    (pad "2" smd roundrect (at 0.484 0 270) (size 0.59 0.64) (layers "F.Cu" "F.Paste" "F.Mask") (roundrect_rratio 0.25)
      (net 1 "GND") (pintype "passive"))
  )
	(footprint "sa800u-baseboard-hw-footprints:C_0402_1005Metric" (layer "F.Cu")
    (tedit 616D63CF)
    (at 87.8 139.875 -90)
    (descr "Capacitor SMD 0402")
    (tags "capacitor SMD 0402")
    (property "Author" "Antmicro")
    (property "Dielectric" "")
    (property "License" "Apache-2.0")
    (property "MPN" "C1005X6S1A105K050BC")
    (property "Manufacturer" "TDK")
    (property "Sheetfile" "usb-pd.kicad_sch")
    (property "Sheetname" "USB-PD")
    (property "Val" "1u")
    (property "Voltage" "")
    (attr smd)
    (fp_text reference "C154" (at 2.595 -3.37 -90) (layer "F.SilkS")
      (effects (font (size 0.7 0.7) (thickness 0.15)) (justify left bottom))
    )
    (fp_text value "C_1u_0402" (at 0 1.4 -90) (layer "F.Fab")
      (effects (font (size 0.7 0.7) (thickness 0.15)) (justify left bottom))
    )
    (fp_text user "License: Apache-2.0" (at -0.932 5.17 -90) (layer "F.Fab") hide
      (effects (font (size 0.7 0.7) (thickness 0.15)) (justify left bottom))
    )
    (fp_text user "${REFERENCE}" (at -0.932 3.168 -90) (layer "F.Fab") hide
      (effects (font (size 0.7 0.7) (thickness 0.15)) (justify left bottom))
    )
    (fp_text user "Author: Antmicro" (at -0.932 4.17 -90) (layer "F.Fab") hide
      (effects (font (size 0.7 0.7) (thickness 0.15)) (justify left bottom))
    )
    (fp_rect (start -0.94 -0.47) (end 0.94 0.47) (layer "F.CrtYd") (width 0.05) (fill none))
    (fp_rect (start -0.499 -0.249) (end 0.499 0.249) (layer "F.Fab") (width 0.15) (fill none))
    (pad "1" smd roundrect (at -0.484 0 270) (size 0.59 0.64) (layers "F.Cu" "F.Paste" "F.Mask") (roundrect_rratio 0.25)
      (net 141 "/USB-PD/VREG_2V7") (pintype "passive"))
    (pad "2" smd roundrect (at 0.484 0 270) (size 0.59 0.64) (layers "F.Cu" "F.Paste" "F.Mask") (roundrect_rratio 0.25)
      (net 1 "GND") (pintype "passive"))
  )
)
